(kicad_pcb
	(version 20260206)
	(generator "pcbnew")
	(generator_version "10.0")
	(general
		(thickness 1.6)
		(legacy_teardrops no)
	)
	(paper "A4")
	(title_block
		(title "04192023_DAF0TMB3IC0_F0TG_MB_C_brd_V02_OCP.brd")
		(comment 1 "Grand Teton / footprints 1278-1286 of 8354")
	)
	(layers
		(0 "F.Cu" signal "TOP")
		(4 "In1.Cu" signal "GND")
		(6 "In2.Cu" signal "IN1")
		(8 "In3.Cu" signal "GND1")
		(10 "In4.Cu" signal "IN2")
		(12 "In5.Cu" signal "GND2")
		(14 "In6.Cu" signal "IN3")
		(16 "In7.Cu" signal "GND3")
		(18 "In8.Cu" signal "VCC")
		(20 "In9.Cu" signal "VCC1")
		(22 "In10.Cu" signal "GND4")
		(24 "In11.Cu" signal "IN4")
		(26 "In12.Cu" signal "GND5")
		(28 "In13.Cu" signal "IN5")
		(30 "In14.Cu" signal "GND6")
		(32 "In15.Cu" signal "IN6")
		(34 "In16.Cu" signal "GND7")
		(2 "B.Cu" signal "BOTTOM")
		(9 "F.Adhes" user "F.Adhesive")
		(11 "B.Adhes" user "B.Adhesive")
		(13 "F.Paste" user "Package Geometry/Pastemask Top")
		(15 "B.Paste" user "Package Geometry/Pastemask Bottom")
		(5 "F.SilkS" user "Ref Des/Silkscreen Top")
		(7 "B.SilkS" user "Ref Des/Silkscreen Bottom")
		(1 "F.Mask" user "Board Geometry/Soldermask Top")
		(3 "B.Mask" user "Board Geometry/Soldermask Bottom")
		(17 "Dwgs.User" user "User.Drawings")
		(19 "Cmts.User" user "User.Comments")
		(21 "Eco1.User" user "User.Eco1")
		(23 "Eco2.User" user "User.Eco2")
		(25 "Edge.Cuts" user "Board Geometry/Outline")
		(27 "Margin" user)
		(31 "F.CrtYd" user "Package Geometry/Place Bound Top")
		(29 "B.CrtYd" user "Package Geometry/Place Bound Bottom")
		(35 "F.Fab" user "Ref Des/Assembly Top")
		(33 "B.Fab" user "Ref Des/Assembly Bottom")
	)
	(footprint ""
		(layer "F.Cu")
		(at 102.767892 -185.697368)
		(property "Reference" "PC316"
			(at 0 0 0)
			(layer "F.SilkS")
			(hide yes)
			(effects
				(font
					(size 1.27 1.27)
				)
			)
		)
		(property "Value" ""
			(at 0 0 0)
			(layer "F.Fab")
			(effects
				(font
					(size 1.27 1.27)
				)
			)
		)
		(duplicate_pad_numbers_are_jumpers no)
		(fp_line
			(start -0.7874 -0.4064)
			(end 0.7874 -0.4064)
			(stroke
				(width 0.1524)
				(type default)
			)
			(layer "F.SilkS")
		)
		(fp_line
			(start -0.7874 0.4064)
			(end -0.7874 -0.4064)
			(stroke
				(width 0.1524)
				(type default)
			)
			(layer "F.SilkS")
		)
		(fp_line
			(start 0.7874 -0.4064)
			(end 0.7874 0.4064)
			(stroke
				(width 0.1524)
				(type default)
			)
			(layer "F.SilkS")
		)
		(fp_line
			(start 0.7874 0.4064)
			(end -0.7874 0.4064)
			(stroke
				(width 0.1524)
				(type default)
			)
			(layer "F.SilkS")
		)
		(fp_line
			(start -0.67945 -0.305054)
			(end -0.12065 -0.305054)
			(stroke
				(width 0.1)
				(type default)
			)
			(layer "F.Fab")
		)
		(fp_line
			(start -0.67945 0.3048)
			(end -0.67945 -0.305054)
			(stroke
				(width 0.1)
				(type default)
			)
			(layer "F.Fab")
		)
		(fp_line
			(start -0.12065 -0.305054)
			(end -0.12065 -0.2794)
			(stroke
				(width 0.1)
				(type default)
			)
			(layer "F.Fab")
		)
		(fp_line
			(start -0.12065 -0.2794)
			(end 0.12065 -0.2794)
			(stroke
				(width 0.1)
				(type default)
			)
			(layer "F.Fab")
		)
		(fp_line
			(start -0.12065 0.2794)
			(end -0.12065 0.3048)
			(stroke
				(width 0.1)
				(type default)
			)
			(layer "F.Fab")
		)
		(fp_line
			(start -0.12065 0.3048)
			(end -0.67945 0.3048)
			(stroke
				(width 0.1)
				(type default)
			)
			(layer "F.Fab")
		)
		(fp_line
			(start 0.120396 0.2794)
			(end -0.12065 0.2794)
			(stroke
				(width 0.1)
				(type default)
			)
			(layer "F.Fab")
		)
		(fp_line
			(start 0.120396 0.3048)
			(end 0.120396 0.2794)
			(stroke
				(width 0.1)
				(type default)
			)
			(layer "F.Fab")
		)
		(fp_line
			(start 0.12065 -0.3048)
			(end 0.67945 -0.3048)
			(stroke
				(width 0.1)
				(type default)
			)
			(layer "F.Fab")
		)
		(fp_line
			(start 0.12065 -0.2794)
			(end 0.12065 -0.3048)
			(stroke
				(width 0.1)
				(type default)
			)
			(layer "F.Fab")
		)
		(fp_line
			(start 0.67945 -0.3048)
			(end 0.67945 0.3048)
			(stroke
				(width 0.1)
				(type default)
			)
			(layer "F.Fab")
		)
		(fp_line
			(start 0.67945 0.3048)
			(end 0.120396 0.3048)
			(stroke
				(width 0.1)
				(type default)
			)
			(layer "F.Fab")
		)
		(pad "1" smd circle
			(at -0.40005 0)
			(size 0 0)
			(layers "F.Cu" "F.Mask" "F.Paste")
			(net "SW_PVDDCR_CPU0_P1_SW3")
		)
		(pad "2" smd circle
			(at 0.40005 0)
			(size 0 0)
			(layers "F.Cu" "F.Mask" "F.Paste")
			(net "SW_PVDDCR_CPU0_P1_SW3_RC")
		)
	)
	(footprint ""
		(layer "F.Cu")
		(at 463.735928 -93.309186)
		(property "Reference" "R3232"
			(at 0 0 0)
			(layer "F.SilkS")
			(hide yes)
			(effects
				(font
					(size 1.27 1.27)
				)
			)
		)
		(property "Value" ""
			(at 0 0 0)
			(layer "F.Fab")
			(effects
				(font
					(size 1.27 1.27)
				)
			)
		)
		(duplicate_pad_numbers_are_jumpers no)
		(fp_line
			(start -0.7874 -0.4064)
			(end 0.7874 -0.4064)
			(stroke
				(width 0.1524)
				(type default)
			)
			(layer "F.SilkS")
		)
		(fp_line
			(start -0.7874 0.4064)
			(end -0.7874 -0.4064)
			(stroke
				(width 0.1524)
				(type default)
			)
			(layer "F.SilkS")
		)
		(fp_line
			(start 0.7874 -0.4064)
			(end 0.7874 0.4064)
			(stroke
				(width 0.1524)
				(type default)
			)
			(layer "F.SilkS")
		)
		(fp_line
			(start 0.7874 0.4064)
			(end -0.7874 0.4064)
			(stroke
				(width 0.1524)
				(type default)
			)
			(layer "F.SilkS")
		)
		(fp_line
			(start -0.67945 -0.305054)
			(end -0.12065 -0.305054)
			(stroke
				(width 0.1)
				(type default)
			)
			(layer "F.Fab")
		)
		(fp_line
			(start -0.67945 0.3048)
			(end -0.67945 -0.305054)
			(stroke
				(width 0.1)
				(type default)
			)
			(layer "F.Fab")
		)
		(fp_line
			(start -0.12065 -0.305054)
			(end -0.12065 -0.2794)
			(stroke
				(width 0.1)
				(type default)
			)
			(layer "F.Fab")
		)
		(fp_line
			(start -0.12065 -0.2794)
			(end 0.12065 -0.2794)
			(stroke
				(width 0.1)
				(type default)
			)
			(layer "F.Fab")
		)
		(fp_line
			(start -0.12065 0.2794)
			(end -0.12065 0.3048)
			(stroke
				(width 0.1)
				(type default)
			)
			(layer "F.Fab")
		)
		(fp_line
			(start -0.12065 0.3048)
			(end -0.67945 0.3048)
			(stroke
				(width 0.1)
				(type default)
			)
			(layer "F.Fab")
		)
		(fp_line
			(start 0.120396 0.2794)
			(end -0.12065 0.2794)
			(stroke
				(width 0.1)
				(type default)
			)
			(layer "F.Fab")
		)
		(fp_line
			(start 0.120396 0.3048)
			(end 0.120396 0.2794)
			(stroke
				(width 0.1)
				(type default)
			)
			(layer "F.Fab")
		)
		(fp_line
			(start 0.12065 -0.3048)
			(end 0.67945 -0.3048)
			(stroke
				(width 0.1)
				(type default)
			)
			(layer "F.Fab")
		)
		(fp_line
			(start 0.12065 -0.2794)
			(end 0.12065 -0.3048)
			(stroke
				(width 0.1)
				(type default)
			)
			(layer "F.Fab")
		)
		(fp_line
			(start 0.67945 -0.3048)
			(end 0.67945 0.3048)
			(stroke
				(width 0.1)
				(type default)
			)
			(layer "F.Fab")
		)
		(fp_line
			(start 0.67945 0.3048)
			(end 0.120396 0.3048)
			(stroke
				(width 0.1)
				(type default)
			)
			(layer "F.Fab")
		)
		(pad "1" smd circle
			(at -0.40005 0)
			(size 0 0)
			(layers "F.Cu" "F.Mask" "F.Paste")
			(net "RST_HP_OCP_SFF_R_N")
		)
		(pad "2" smd circle
			(at 0.40005 0)
			(size 0 0)
			(layers "F.Cu" "F.Mask" "F.Paste")
			(net "GND")
		)
	)
	(footprint ""
		(layer "F.Cu")
		(at 129.084832 -75.466956)
		(property "Reference" "PL6001"
			(at -5.210048 -5.253482 0)
			(unlocked yes)
			(layer "F.SilkS")
			(effects
				(font
					(size 0.7874 0.5842)
					(thickness 0.1524)
				)
				(justify left)
			)
		)
		(property "Value" ""
			(at 0 0 0)
			(layer "F.Fab")
			(effects
				(font
					(size 1.27 1.27)
				)
			)
		)
		(duplicate_pad_numbers_are_jumpers no)
		(fp_line
			(start -3.6576 -3.350006)
			(end 3.64998 -3.350006)
			(stroke
				(width 0.1524)
				(type default)
			)
			(layer "F.SilkS")
		)
		(fp_line
			(start -3.64998 -1.8034)
			(end -3.64998 -3.350006)
			(stroke
				(width 0.1524)
				(type default)
			)
			(layer "F.SilkS")
		)
		(fp_line
			(start -3.64998 3.350006)
			(end -3.64998 1.8288)
			(stroke
				(width 0.1524)
				(type default)
			)
			(layer "F.SilkS")
		)
		(fp_line
			(start 3.64998 -3.350006)
			(end 3.64998 -1.8034)
			(stroke
				(width 0.1524)
				(type default)
			)
			(layer "F.SilkS")
		)
		(fp_line
			(start 3.64998 1.8034)
			(end 3.64998 3.350006)
			(stroke
				(width 0.1524)
				(type default)
			)
			(layer "F.SilkS")
		)
		(fp_line
			(start 3.64998 3.350006)
			(end -3.64998 3.350006)
			(stroke
				(width 0.1524)
				(type default)
			)
			(layer "F.SilkS")
		)
		(fp_line
			(start -3.64998 -3.350006)
			(end 3.64998 -3.350006)
			(stroke
				(width 0.1)
				(type default)
			)
			(layer "F.Fab")
		)
		(fp_line
			(start -3.64998 3.350006)
			(end -3.64998 -3.350006)
			(stroke
				(width 0.1)
				(type default)
			)
			(layer "F.Fab")
		)
		(fp_line
			(start 3.64998 -3.350006)
			(end 3.64998 3.350006)
			(stroke
				(width 0.1)
				(type default)
			)
			(layer "F.Fab")
		)
		(fp_line
			(start 3.64998 3.350006)
			(end -3.64998 3.350006)
			(stroke
				(width 0.1)
				(type default)
			)
			(layer "F.Fab")
		)
		(pad "1" smd rect
			(at -2.92481 0)
			(size 2.15392 3.302)
			(layers "F.Cu" "F.Mask" "F.Paste")
			(net "SW_P1V2_AUX_PH")
		)
		(pad "2" smd rect
			(at 2.92481 0)
			(size 2.15392 3.302)
			(layers "F.Cu" "F.Mask" "F.Paste")
			(net "P1V2_AUX")
		)
	)
	(footprint ""
		(layer "F.Cu")
		(at 378.449078 -356.362508 180)
		(property "Reference" ""
			(at 0 0 180)
			(layer "F.SilkS")
			(hide yes)
			(effects
				(font
					(size 1.27 1.27)
				)
			)
		)
		(property "Value" ""
			(at 0 0 180)
			(layer "F.Fab")
			(effects
				(font
					(size 1.27 1.27)
				)
			)
		)
		(duplicate_pad_numbers_are_jumpers no)
		(pad "1" smd circle
			(at 0 0 180)
			(size 0.9906 0.9906)
			(layers "F.Cu" "F.Mask" "F.Paste")
			(net "Net_47")
		)
		(zone
			(layer "F.Cu")
			(hatch none 0.5)
			(connect_pads
				(clearance 0)
			)
			(min_thickness 0.25)
			(keepout
				(tracks not_allowed)
				(vias allowed)
				(pads allowed)
				(copperpour not_allowed)
				(footprints allowed)
			)
			(placement
				(enabled no)
				(sheetname "")
			)
			(fill
				(thermal_gap 0.5)
				(thermal_bridge_width 0.5)
				(island_removal_mode 0)
			)
			(polygon
				(pts
					(arc
						(start 380.074678 -356.362508)
						(mid 376.823478 -356.362508)
						(end 380.074678 -356.362508)
					)
				)
			)
		)
	)
	(footprint ""
		(layer "F.Cu")
		(at 363.044486 -406.172416 180)
		(property "Reference" "Q9002"
			(at -3.329432 -1.883156 90)
			(unlocked yes)
			(layer "F.SilkS")
			(effects
				(font
					(size 0.7874 0.5842)
					(thickness 0.1524)
				)
				(justify left)
			)
		)
		(property "Value" ""
			(at 0 0 180)
			(layer "F.Fab")
			(effects
				(font
					(size 1.27 1.27)
				)
			)
		)
		(duplicate_pad_numbers_are_jumpers no)
		(fp_line
			(start 1.332738 1.100074)
			(end -1.332738 1.100074)
			(stroke
				(width 0.1524)
				(type default)
			)
			(layer "F.SilkS")
		)
		(fp_line
			(start 1.332738 -1.100074)
			(end 1.332738 1.100074)
			(stroke
				(width 0.1524)
				(type default)
			)
			(layer "F.SilkS")
		)
		(fp_line
			(start 0.4826 -1.100074)
			(end 1.332738 -1.100074)
			(stroke
				(width 0.1524)
				(type default)
			)
			(layer "F.SilkS")
		)
		(fp_line
			(start 0 -0.541274)
			(end 0.4826 -1.100074)
			(stroke
				(width 0.1524)
				(type default)
			)
			(layer "F.SilkS")
		)
		(fp_line
			(start -0.4826 -1.100074)
			(end 0 -0.541274)
			(stroke
				(width 0.1524)
				(type default)
			)
			(layer "F.SilkS")
		)
		(fp_line
			(start -1.332738 1.100074)
			(end -1.332738 -1.100074)
			(stroke
				(width 0.1524)
				(type default)
			)
			(layer "F.SilkS")
		)
		(fp_line
			(start -1.332738 -1.100074)
			(end -0.4826 -1.100074)
			(stroke
				(width 0.1524)
				(type default)
			)
			(layer "F.SilkS")
		)
		(fp_poly
			(pts
				(xy -2.659634 -0.318262) (xy -2.659634 -1.020318) (xy -1.957578 -0.66929)
			)
			(stroke
				(width 0)
				(type default)
			)
			(fill yes)
			(layer "F.SilkS")
		)
		(fp_line
			(start 0.674878 1.100074)
			(end -0.674878 1.100074)
			(stroke
				(width 0.1)
				(type default)
			)
			(layer "F.Fab")
		)
		(fp_line
			(start 0.674878 -1.100074)
			(end 0.674878 1.100074)
			(stroke
				(width 0.1)
				(type default)
			)
			(layer "F.Fab")
		)
		(fp_line
			(start -0.674878 1.100074)
			(end -0.674878 -1.100074)
			(stroke
				(width 0.1)
				(type default)
			)
			(layer "F.Fab")
		)
		(fp_line
			(start -0.674878 -1.100074)
			(end 0.674878 -1.100074)
			(stroke
				(width 0.1)
				(type default)
			)
			(layer "F.Fab")
		)
		(fp_poly
			(pts
				(xy -2.2352 -0.298958) (xy -2.2352 -1.001014) (xy -1.533144 -0.649986)
			)
			(stroke
				(width 0)
				(type default)
			)
			(fill yes)
			(layer "F.Fab")
		)
		(pad "1" smd rect
			(at -0.94996 -0.649986 270)
			(size 0.4318 0.508)
			(layers "F.Cu" "F.Mask" "F.Paste")
			(net "GND")
		)
		(pad "2" smd rect
			(at -0.94996 0 270)
			(size 0.4318 0.508)
			(layers "F.Cu" "F.Mask" "F.Paste")
			(net "PRSNT_CABLE_GPU_A3_N")
		)
		(pad "3" smd rect
			(at -0.94996 0.649986 270)
			(size 0.4318 0.508)
			(layers "F.Cu" "F.Mask" "F.Paste")
			(net "PRSNT_CABLE_GPU_A3_ISO_N")
		)
		(pad "4" smd rect
			(at 0.94996 0.649986 270)
			(size 0.4318 0.508)
			(layers "F.Cu" "F.Mask" "F.Paste")
			(net "GND")
		)
		(pad "5" smd rect
			(at 0.94996 0 270)
			(size 0.4318 0.508)
			(layers "F.Cu" "F.Mask" "F.Paste")
			(net "PRSNT_CABLE_GPU_A3")
		)
		(pad "6" smd rect
			(at 0.94996 -0.649986 270)
			(size 0.4318 0.508)
			(layers "F.Cu" "F.Mask" "F.Paste")
			(net "PRSNT_CABLE_GPU_A3")
		)
	)
	(footprint ""
		(layer "F.Cu")
		(at 139.794742 -385.5212 90)
		(property "Reference" "R904"
			(at 0 0 90)
			(layer "F.SilkS")
			(hide yes)
			(effects
				(font
					(size 1.27 1.27)
				)
			)
		)
		(property "Value" ""
			(at 0 0 90)
			(layer "F.Fab")
			(effects
				(font
					(size 1.27 1.27)
				)
			)
		)
		(duplicate_pad_numbers_are_jumpers no)
		(fp_line
			(start 0.32512 -0.175006)
			(end 0.32512 0.175006)
			(stroke
				(width 0.1)
				(type default)
			)
			(layer "F.Fab")
		)
		(fp_line
			(start -0.32512 -0.175006)
			(end 0.32512 -0.175006)
			(stroke
				(width 0.1)
				(type default)
			)
			(layer "F.Fab")
		)
		(fp_line
			(start 0.32512 0.175006)
			(end -0.32512 0.175006)
			(stroke
				(width 0.1)
				(type default)
			)
			(layer "F.Fab")
		)
		(fp_line
			(start -0.32512 0.175006)
			(end -0.32512 -0.175006)
			(stroke
				(width 0.1)
				(type default)
			)
			(layer "F.Fab")
		)
		(pad "1" smd rect
			(at -0.2667 0 90)
			(size 0.3048 0.381)
			(layers "F.Cu" "F.Mask" "F.Paste")
			(net "P1V8_CPU1_RT_1D")
		)
		(pad "2" smd rect
			(at 0.2667 0 270)
			(size 0.3048 0.381)
			(layers "F.Cu" "F.Mask" "F.Paste")
			(net "RT_CPU1_P3_ADDR2")
		)
	)
	(footprint ""
		(layer "F.Cu")
		(at 432.636676 -93.922342)
		(property "Reference" "R3602"
			(at 0 0 0)
			(layer "F.SilkS")
			(hide yes)
			(effects
				(font
					(size 1.27 1.27)
				)
			)
		)
		(property "Value" ""
			(at 0 0 0)
			(layer "F.Fab")
			(effects
				(font
					(size 1.27 1.27)
				)
			)
		)
		(duplicate_pad_numbers_are_jumpers no)
		(fp_line
			(start -0.7874 -0.4064)
			(end 0.7874 -0.4064)
			(stroke
				(width 0.1524)
				(type default)
			)
			(layer "F.SilkS")
		)
		(fp_line
			(start -0.7874 0.4064)
			(end -0.7874 -0.4064)
			(stroke
				(width 0.1524)
				(type default)
			)
			(layer "F.SilkS")
		)
		(fp_line
			(start 0.7874 -0.4064)
			(end 0.7874 0.4064)
			(stroke
				(width 0.1524)
				(type default)
			)
			(layer "F.SilkS")
		)
		(fp_line
			(start 0.7874 0.4064)
			(end -0.7874 0.4064)
			(stroke
				(width 0.1524)
				(type default)
			)
			(layer "F.SilkS")
		)
		(fp_line
			(start -0.67945 -0.305054)
			(end -0.12065 -0.305054)
			(stroke
				(width 0.1)
				(type default)
			)
			(layer "F.Fab")
		)
		(fp_line
			(start -0.67945 0.3048)
			(end -0.67945 -0.305054)
			(stroke
				(width 0.1)
				(type default)
			)
			(layer "F.Fab")
		)
		(fp_line
			(start -0.12065 -0.305054)
			(end -0.12065 -0.2794)
			(stroke
				(width 0.1)
				(type default)
			)
			(layer "F.Fab")
		)
		(fp_line
			(start -0.12065 -0.2794)
			(end 0.12065 -0.2794)
			(stroke
				(width 0.1)
				(type default)
			)
			(layer "F.Fab")
		)
		(fp_line
			(start -0.12065 0.2794)
			(end -0.12065 0.3048)
			(stroke
				(width 0.1)
				(type default)
			)
			(layer "F.Fab")
		)
		(fp_line
			(start -0.12065 0.3048)
			(end -0.67945 0.3048)
			(stroke
				(width 0.1)
				(type default)
			)
			(layer "F.Fab")
		)
		(fp_line
			(start 0.120396 0.2794)
			(end -0.12065 0.2794)
			(stroke
				(width 0.1)
				(type default)
			)
			(layer "F.Fab")
		)
		(fp_line
			(start 0.120396 0.3048)
			(end 0.120396 0.2794)
			(stroke
				(width 0.1)
				(type default)
			)
			(layer "F.Fab")
		)
		(fp_line
			(start 0.12065 -0.3048)
			(end 0.67945 -0.3048)
			(stroke
				(width 0.1)
				(type default)
			)
			(layer "F.Fab")
		)
		(fp_line
			(start 0.12065 -0.2794)
			(end 0.12065 -0.3048)
			(stroke
				(width 0.1)
				(type default)
			)
			(layer "F.Fab")
		)
		(fp_line
			(start 0.67945 -0.3048)
			(end 0.67945 0.3048)
			(stroke
				(width 0.1)
				(type default)
			)
			(layer "F.Fab")
		)
		(fp_line
			(start 0.67945 0.3048)
			(end 0.120396 0.3048)
			(stroke
				(width 0.1)
				(type default)
			)
			(layer "F.Fab")
		)
		(pad "1" smd circle
			(at -0.40005 0)
			(size 0 0)
			(layers "F.Cu" "F.Mask" "F.Paste")
			(net "P3V3_OCP_SFF_R")
		)
		(pad "2" smd circle
			(at 0.40005 0)
			(size 0 0)
			(layers "F.Cu" "F.Mask" "F.Paste")
			(net "VSENSE_P3V3_INA230_1_INP")
		)
	)
	(footprint ""
		(layer "F.Cu")
		(at 461.460088 -160.499806)
		(property "Reference" "H98"
			(at -3.056382 -5.99186 0)
			(unlocked yes)
			(layer "F.SilkS")
			(effects
				(font
					(size 0.7874 0.5842)
					(thickness 0.1524)
				)
				(justify left)
			)
		)
		(property "Value" ""
			(at 0 0 0)
			(layer "F.Fab")
			(effects
				(font
					(size 1.27 1.27)
				)
			)
		)
		(duplicate_pad_numbers_are_jumpers no)
		(pad "1" thru_hole circle
			(at 0 0)
			(size 10.0076 10.0076)
			(drill 5.6134)
			(layers "*.Cu" "*.Mask")
			(remove_unused_layers no)
			(net "GND")
			(clearance -1.9431)
		)
	)
	(footprint ""
		(layer "F.Cu")
		(at 233.2228 -283.5148)
		(property "Reference" "PC6521"
			(at 0 0 0)
			(layer "F.SilkS")
			(hide yes)
			(effects
				(font
					(size 1.27 1.27)
				)
			)
		)
		(property "Value" ""
			(at 0 0 0)
			(layer "F.Fab")
			(effects
				(font
					(size 1.27 1.27)
				)
			)
		)
		(duplicate_pad_numbers_are_jumpers no)
		(fp_line
			(start -1.524 -0.762)
			(end 1.524 -0.762)
			(stroke
				(width 0.1524)
				(type default)
			)
			(layer "F.SilkS")
		)
		(fp_line
			(start -1.524 0.762)
			(end -1.524 -0.762)
			(stroke
				(width 0.1524)
				(type default)
			)
			(layer "F.SilkS")
		)
		(fp_line
			(start 1.524 -0.762)
			(end 1.524 0.762)
			(stroke
				(width 0.1524)
				(type default)
			)
			(layer "F.SilkS")
		)
		(fp_line
			(start 1.524 0.762)
			(end -1.524 0.762)
			(stroke
				(width 0.1524)
				(type default)
			)
			(layer "F.SilkS")
		)
		(fp_line
			(start -1.1049 -0.724916)
			(end -1.1049 0.724916)
			(stroke
				(width 0.1)
				(type default)
			)
			(layer "F.Fab")
		)
		(fp_line
			(start -1.1049 0.724916)
			(end 1.1049 0.724916)
			(stroke
				(width 0.1)
				(type default)
			)
			(layer "F.Fab")
		)
		(fp_line
			(start 1.1049 -0.724916)
			(end -1.1049 -0.724916)
			(stroke
				(width 0.1)
				(type default)
			)
			(layer "F.Fab")
		)
		(fp_line
			(start 1.1049 0.724916)
			(end 1.1049 -0.724916)
			(stroke
				(width 0.1)
				(type default)
			)
			(layer "F.Fab")
		)
		(pad "1" smd rect
			(at -0.889 0 180)
			(size 1.016 1.27)
			(layers "F.Cu" "F.Mask" "F.Paste")
			(net "SW_P12V_AUX_P1V8_RETIMER_CPU1_FLT")
		)
		(pad "2" smd rect
			(at 0.889 0 180)
			(size 1.016 1.27)
			(layers "F.Cu" "F.Mask" "F.Paste")
			(net "GND")
		)
	)
)
